(kicad_pcb
	(version 20241229)
	(generator "pcbnew")
	(generator_version "9.0")
	(general
		(thickness 1.6642)
		(legacy_teardrops no)
	)
	(paper "A3")
	(title_block
		(title "PolarFire SoM")
		(date "2025-07-22")
		(rev "1.1.4")
		(company "Antmicro Ltd")
		(comment 1 "www.antmicro.com")
		(comment 9 "footprint 85 of 470 (U1), pads 427-484 of 484")
	)
	(layers
		(0 "F.Cu" mixed)
		(4 "In1.Cu" power)
		(6 "In2.Cu" signal)
		(8 "In3.Cu" power)
		(10 "In4.Cu" signal)
		(12 "In5.Cu" power)
		(14 "In6.Cu" power)
		(16 "In7.Cu" signal)
		(18 "In8.Cu" power)
		(20 "In9.Cu" signal)
		(22 "In10.Cu" power)
		(24 "In11.Cu" signal)
		(26 "In12.Cu" signal)
		(2 "B.Cu" mixed)
		(9 "F.Adhes" user "F.Adhesive")
		(11 "B.Adhes" user "B.Adhesive")
		(13 "F.Paste" user)
		(15 "B.Paste" user)
		(5 "F.SilkS" user "F.Silkscreen")
		(7 "B.SilkS" user "B.Silkscreen")
		(1 "F.Mask" user)
		(3 "B.Mask" user)
		(17 "Dwgs.User" user "User.Drawings")
		(19 "Cmts.User" user "User.Comments")
		(21 "Eco1.User" user "User.Eco1")
		(23 "Eco2.User" user "User.Eco2")
		(25 "Edge.Cuts" user)
		(27 "Margin" user)
		(31 "F.CrtYd" user "F.Courtyard")
		(29 "B.CrtYd" user "B.Courtyard")
		(35 "F.Fab" user)
		(33 "B.Fab" user)
	)
	(footprint "antmicro-footprints:BGA-484_19x19mm_Layout22x22_P0.8mm_FCVG484"
		(layer "F.Cu")
		(at 197.699 132.701 -90)
		(descr "FCVG484, 19.0x19.0mm, 484 Ball, 22x22 Layout, 0.8mm Pitch")
		(tags "BGA 484 0.8")
		(property "Reference" "U1"
			(at 0 -10.8 270)
			(layer "F.SilkS")
			(effects
				(font
					(size 0.7 0.7)
					(thickness 0.15)
				)
				(justify left bottom)
			)
		)
		(property "Value" "MPFS250T-FCVG484"
			(at 0 11.5 270)
			(layer "F.Fab")
			(hide yes)
			(effects
				(font
					(size 0.7 0.7)
					(thickness 0.15)
				)
				(justify left bottom)
			)
		)
		(property "Datasheet" "https://ww1.microchip.com/downloads/aemDocuments/documents/FPGA/ProductDocuments/DataSheets/PolarFire-SoC-Datasheet-DS00004248.pdf"
			(at 0 0 270)
			(layer "F.Fab")
			(hide yes)
			(effects
				(font
					(size 1.27 1.27)
					(thickness 0.15)
				)
			)
		)
		(property "Description" "RISC-V System On Chip (SOC) IC PolarFire® FPGA - 254K Logic Modules 484-FCBGA (19x19)"
			(at 0 0 270)
			(layer "F.Fab")
			(hide yes)
			(effects
				(font
					(size 1.27 1.27)
					(thickness 0.15)
				)
			)
		)
		(property "MPN" "MPFS250T-FCVG484E"
			(at 0 0 270)
			(unlocked yes)
			(layer "F.Fab")
			(hide yes)
			(effects
				(font
					(size 1 1)
					(thickness 0.15)
				)
			)
		)
		(property "Manufacturer" "Microchip Technology"
			(at 0 0 270)
			(unlocked yes)
			(layer "F.Fab")
			(hide yes)
			(effects
				(font
					(size 1 1)
					(thickness 0.15)
				)
			)
		)
		(property "VSD_class" "MPFS250T"
			(at 0 0 270)
			(unlocked yes)
			(layer "F.Fab")
			(hide yes)
			(effects
				(font
					(size 1 1)
					(thickness 0.15)
				)
			)
		)
		(property "Author" "Antmicro"
			(at 0 0 270)
			(unlocked yes)
			(layer "F.Fab")
			(hide yes)
			(effects
				(font
					(size 1 1)
					(thickness 0.15)
				)
			)
		)
		(property "License" "Apache-2.0"
			(at 0 0 270)
			(unlocked yes)
			(layer "F.Fab")
			(hide yes)
			(effects
				(font
					(size 1 1)
					(thickness 0.15)
				)
			)
		)
		(sheetname "/FPGA Config/")
		(sheetfile "fpga-config.kicad_sch")
		(attr smd)
		(pad "V9" smd circle
			(at -2 5.2 270)
			(size 0.45 0.45)
			(layers "F.Cu" "F.Mask" "F.Paste")
			(net 599 "/FPGA MSS/LPDDR4.DQS3_N")
			(pinfunction "MSS_DDR_DQS_N3")
			(pintype "bidirectional")
			(die_length 8.21899)
		)
		(pad "V10" smd circle
			(at -1.2 5.2 270)
			(size 0.45 0.45)
			(layers "F.Cu" "F.Mask" "F.Paste")
			(net 600 "/FPGA MSS/LPDDR4.DQ21")
			(pinfunction "MSS_DDR_DQ21")
			(pintype "bidirectional")
			(die_length 8.68063)
		)
		(pad "V11" smd circle
			(at -0.401 5.2 270)
			(size 0.45 0.45)
			(layers "F.Cu" "F.Mask" "F.Paste")
			(net 601 "/FPGA MSS/LPDDR4.DQ20")
			(pinfunction "MSS_DDR_DQ20")
			(pintype "bidirectional")
			(die_length 9.2829)
		)
		(pad "V12" smd circle
			(at 0.4 5.2 270)
			(size 0.45 0.45)
			(layers "F.Cu" "F.Mask" "F.Paste")
			(net 454 "unconnected-(U1A-HSIO92NB0-PadV12)")
			(pinfunction "HSIO92NB0")
			(pintype "bidirectional+no_connect")
			(die_length 7.65608)
		)
		(pad "V13" smd circle
			(at 1.199 5.2 270)
			(size 0.45 0.45)
			(layers "F.Cu" "F.Mask" "F.Paste")
			(net 417 "GND")
			(pinfunction "VSS")
			(pintype "passive")
		)
		(pad "V14" smd circle
			(at 1.999 5.2 270)
			(size 0.45 0.45)
			(layers "F.Cu" "F.Mask" "F.Paste")
			(net 455 "unconnected-(U1A-HSIO90PB0{slash}CLKIN_N_3{slash}CCC_NW_CLKIN_N_3-PadV14)")
			(pinfunction "HSIO90PB0/CLKIN_N_3/CCC_NW_CLKIN_N_3")
			(pintype "bidirectional+no_connect")
			(die_length 7.13069)
		)
		(pad "V15" smd circle
			(at 2.799 5.2 270)
			(size 0.45 0.45)
			(layers "F.Cu" "F.Mask" "F.Paste")
			(net 456 "unconnected-(U1A-HSIO90NB0-PadV15)")
			(pinfunction "HSIO90NB0")
			(pintype "bidirectional+no_connect")
			(die_length 7.12976)
		)
		(pad "V16" smd circle
			(at 3.6 5.2 270)
			(size 0.45 0.45)
			(layers "F.Cu" "F.Mask" "F.Paste")
			(net 304 "/FPGA HSIO/Crosslink_B2.D7")
			(pinfunction "HSIO76NB0")
			(pintype "bidirectional")
			(die_length 6.53981)
		)
		(pad "V17" smd circle
			(at 4.4 5.2 270)
			(size 0.45 0.45)
			(layers "F.Cu" "F.Mask" "F.Paste")
			(net 327 "/FPGA HSIO/Crosslink_B1.D4")
			(pinfunction "HSIO76PB0")
			(pintype "bidirectional")
			(die_length 6.54753)
		)
		(pad "V18" smd circle
			(at 5.2 5.2 270)
			(size 0.45 0.45)
			(layers "F.Cu" "F.Mask" "F.Paste")
			(net 48 "+1V8")
			(pinfunction "VDDI0")
			(pintype "passive")
		)
		(pad "V19" smd circle
			(at 5.999 5.2 270)
			(size 0.45 0.45)
			(layers "F.Cu" "F.Mask" "F.Paste")
			(net 328 "/FPGA HSIO/Crosslink_B1.D6")
			(pinfunction "HSIO72NB0")
			(pintype "bidirectional")
			(die_length 8.19662)
		)
		(pad "V20" smd circle
			(at 6.799 5.2 270)
			(size 0.45 0.45)
			(layers "F.Cu" "F.Mask" "F.Paste")
			(net 329 "/FPGA HSIO/Crosslink_B2.D1")
			(pinfunction "HSIO72PB0/CLKIN_N_9/CCC_NE_CLKIN_N_9")
			(pintype "bidirectional")
			(die_length 8.20769)
		)
		(pad "V21" smd circle
			(at 7.599 5.2 270)
			(size 0.45 0.45)
			(layers "F.Cu" "F.Mask" "F.Paste")
			(net 331 "/FPGA HSIO/Crosslink_B2.PCLK")
			(pinfunction "HSIO68NB0")
			(pintype "bidirectional")
			(die_length 6.55804)
		)
		(pad "V22" smd circle
			(at 8.4 5.2 270)
			(size 0.45 0.45)
			(layers "F.Cu" "F.Mask" "F.Paste")
			(net 335 "/FPGA HSIO/Crosslink_B1.HSYNC")
			(pinfunction "HSIO66NB0")
			(pintype "bidirectional")
			(die_length 6.64242)
		)
		(pad "W1" smd circle
			(at -8.401 5.999 270)
			(size 0.45 0.45)
			(layers "F.Cu" "F.Mask" "F.Paste")
			(net 457 "unconnected-(U1G-MSS_DDR_DQ35-PadW1)")
			(pinfunction "MSS_DDR_DQ35")
			(pintype "bidirectional+no_connect")
			(die_length 5.04829)
		)
		(pad "W2" smd circle
			(at -7.6 5.999 270)
			(size 0.45 0.45)
			(layers "F.Cu" "F.Mask" "F.Paste")
			(net 458 "unconnected-(U1G-MSS_DDR_DQ34-PadW2)")
			(pinfunction "MSS_DDR_DQ34")
			(pintype "bidirectional+no_connect")
			(die_length 4.45648)
		)
		(pad "W3" smd circle
			(at -6.8 5.999 270)
			(size 0.45 0.45)
			(layers "F.Cu" "F.Mask" "F.Paste")
			(net 459 "unconnected-(U1G-MSS_DDR_DQ33-PadW3)")
			(pinfunction "MSS_DDR_DQ33")
			(pintype "bidirectional+no_connect")
			(die_length 3.88376)
		)
		(pad "W4" smd circle
			(at -6 5.999 270)
			(size 0.45 0.45)
			(layers "F.Cu" "F.Mask" "F.Paste")
			(net 460 "unconnected-(U1G-MSS_DDR_DQ32-PadW4)")
			(pinfunction "MSS_DDR_DQ32")
			(pintype "bidirectional+no_connect")
			(die_length 4.30238)
		)
		(pad "W5" smd circle
			(at -5.201 5.999 270)
			(size 0.45 0.45)
			(layers "F.Cu" "F.Mask" "F.Paste")
			(net 2 "+1V1")
			(pinfunction "VDDI6")
			(pintype "passive")
		)
		(pad "W6" smd circle
			(at -4.401 5.999 270)
			(size 0.45 0.45)
			(layers "F.Cu" "F.Mask" "F.Paste")
			(net 602 "/FPGA MSS/LPDDR4.DQS1_N")
			(pinfunction "MSS_DDR_DQS_N1")
			(pintype "bidirectional")
			(die_length 6.70831)
		)
		(pad "W7" smd circle
			(at -3.601 5.999 270)
			(size 0.45 0.45)
			(layers "F.Cu" "F.Mask" "F.Paste")
			(net 603 "/FPGA MSS/LPDDR4.DQ9")
			(pinfunction "MSS_DDR_DQ9")
			(pintype "bidirectional")
			(die_length 6.57901)
		)
		(pad "W8" smd circle
			(at -2.8 5.999 270)
			(size 0.45 0.45)
			(layers "F.Cu" "F.Mask" "F.Paste")
			(net 604 "/FPGA MSS/LPDDR4.DQ8")
			(pinfunction "MSS_DDR_DQ8")
			(pintype "bidirectional")
			(die_length 7.65979)
		)
		(pad "W9" smd circle
			(at -2 5.999 270)
			(size 0.45 0.45)
			(layers "F.Cu" "F.Mask" "F.Paste")
			(net 605 "/FPGA MSS/LPDDR4.DQ17")
			(pinfunction "MSS_DDR_DQ17")
			(pintype "bidirectional")
			(die_length 6.80016)
		)
		(pad "W10" smd circle
			(at -1.2 5.999 270)
			(size 0.45 0.45)
			(layers "F.Cu" "F.Mask" "F.Paste")
			(net 417 "GND")
			(pinfunction "VSS")
			(pintype "passive")
		)
		(pad "W11" smd circle
			(at -0.401 5.999 270)
			(size 0.45 0.45)
			(layers "F.Cu" "F.Mask" "F.Paste")
			(net 606 "/FPGA MSS/LPDDR4.DQ23")
			(pinfunction "MSS_DDR_DQ23")
			(pintype "bidirectional")
			(die_length 7.37032)
		)
		(pad "W12" smd circle
			(at 0.4 5.999 270)
			(size 0.45 0.45)
			(layers "F.Cu" "F.Mask" "F.Paste")
			(net 336 "/FPGA HSIO/PF_CLK")
			(pinfunction "HSIO92PB0/CLKIN_N_2/CCC_NW_CLKIN_N_2/CCC_NW_PLL1_OUT0")
			(pintype "bidirectional")
			(die_length 7.66699)
		)
		(pad "W13" smd circle
			(at 1.199 5.999 270)
			(size 0.45 0.45)
			(layers "F.Cu" "F.Mask" "F.Paste")
			(net 462 "unconnected-(U1A-HSIO89PB0-PadW13)")
			(pinfunction "HSIO89PB0")
			(pintype "bidirectional+no_connect")
			(die_length 5.70016)
		)
		(pad "W14" smd circle
			(at 1.999 5.999 270)
			(size 0.45 0.45)
			(layers "F.Cu" "F.Mask" "F.Paste")
			(net 463 "unconnected-(U1A-HSIO87NB0{slash}DQS-PadW14)")
			(pinfunction "HSIO87NB0/DQS")
			(pintype "bidirectional+no_connect")
			(die_length 6.51699)
		)
		(pad "W15" smd circle
			(at 2.799 5.999 270)
			(size 0.45 0.45)
			(layers "F.Cu" "F.Mask" "F.Paste")
			(net 48 "+1V8")
			(pinfunction "VDDI0")
			(pintype "passive")
		)
		(pad "W16" smd circle
			(at 3.6 5.999 270)
			(size 0.45 0.45)
			(layers "F.Cu" "F.Mask" "F.Paste")
			(net 464 "unconnected-(U1A-HSIO83PB0-PadW16)")
			(pinfunction "HSIO83PB0")
			(pintype "bidirectional+no_connect")
			(die_length 6.04706)
		)
		(pad "W17" smd circle
			(at 4.4 5.999 270)
			(size 0.45 0.45)
			(layers "F.Cu" "F.Mask" "F.Paste")
			(net 465 "unconnected-(U1A-HSIO83NB0-PadW17)")
			(pinfunction "HSIO83NB0")
			(pintype "bidirectional+no_connect")
			(die_length 6.04459)
		)
		(pad "W18" smd circle
			(at 5.2 5.999 270)
			(size 0.45 0.45)
			(layers "F.Cu" "F.Mask" "F.Paste")
			(net 466 "unconnected-(U1A-HSIO79NB0-PadW18)")
			(pinfunction "HSIO79NB0")
			(pintype "bidirectional+no_connect")
			(die_length 6.53818)
		)
		(pad "W19" smd circle
			(at 5.999 5.999 270)
			(size 0.45 0.45)
			(layers "F.Cu" "F.Mask" "F.Paste")
			(net 337 "/FPGA HSIO/Crosslink_B1.D5")
			(pinfunction "HSIO79PB0")
			(pintype "bidirectional")
			(die_length 6.51467)
		)
		(pad "W20" smd circle
			(at 6.799 5.999 270)
			(size 0.45 0.45)
			(layers "F.Cu" "F.Mask" "F.Paste")
			(net 417 "GND")
			(pinfunction "VSS")
			(pintype "passive")
		)
		(pad "W21" smd circle
			(at 7.599 5.999 270)
			(size 0.45 0.45)
			(layers "F.Cu" "F.Mask" "F.Paste")
			(net 338 "/FPGA HSIO/Crosslink_B2.HSYNC")
			(pinfunction "HSIO68PB0/CCC_NE_CLKIN_N_10/CCC_NE_PLL0_OUT0")
			(pintype "bidirectional")
			(die_length 6.54838)
		)
		(pad "W22" smd circle
			(at 8.4 5.999 270)
			(size 0.45 0.45)
			(layers "F.Cu" "F.Mask" "F.Paste")
			(net 339 "/FPGA HSIO/Crosslink_B1.VSYNC")
			(pinfunction "HSIO66PB0/CCC_NE_CLKIN_N_11")
			(pintype "bidirectional")
			(die_length 6.65293)
		)
		(pad "Y1" smd circle
			(at -8.401 6.799 270)
			(size 0.45 0.45)
			(layers "F.Cu" "F.Mask" "F.Paste")
			(net 607 "/FPGA MSS/LPDDR4.DQ2")
			(pinfunction "MSS_DDR_DQ2")
			(pintype "bidirectional")
			(die_length 5.78605)
		)
		(pad "Y2" smd circle
			(at -7.6 6.799 270)
			(size 0.45 0.45)
			(layers "F.Cu" "F.Mask" "F.Paste")
			(net 2 "+1V1")
			(pinfunction "VDDI6")
			(pintype "passive")
		)
		(pad "Y3" smd circle
			(at -6.8 6.799 270)
			(size 0.45 0.45)
			(layers "F.Cu" "F.Mask" "F.Paste")
			(net 608 "/FPGA MSS/LPDDR4.DQ0")
			(pinfunction "MSS_DDR_DQ0")
			(pintype "bidirectional")
			(die_length 5.09962)
		)
		(pad "Y4" smd circle
			(at -6 6.799 270)
			(size 0.45 0.45)
			(layers "F.Cu" "F.Mask" "F.Paste")
			(net 609 "/FPGA MSS/LPDDR4.DQ1")
			(pinfunction "MSS_DDR_DQ1")
			(pintype "bidirectional")
			(die_length 5.44242)
		)
		(pad "Y5" smd circle
			(at -5.201 6.799 270)
			(size 0.45 0.45)
			(layers "F.Cu" "F.Mask" "F.Paste")
			(net 610 "/FPGA MSS/LPDDR4.DQ4")
			(pinfunction "MSS_DDR_DQ4")
			(pintype "bidirectional")
			(die_length 4.77603)
		)
		(pad "Y6" smd circle
			(at -4.401 6.799 270)
			(size 0.45 0.45)
			(layers "F.Cu" "F.Mask" "F.Paste")
			(net 611 "/FPGA MSS/LPDDR4.DQS1_P")
			(pinfunction "MSS_DDR_DQS_P1")
			(pintype "bidirectional")
			(die_length 6.71775)
		)
		(pad "Y7" smd circle
			(at -3.601 6.799 270)
			(size 0.45 0.45)
			(layers "F.Cu" "F.Mask" "F.Paste")
			(net 417 "GND")
			(pinfunction "VSS")
			(pintype "passive")
		)
		(pad "Y8" smd circle
			(at -2.8 6.799 270)
			(size 0.45 0.45)
			(layers "F.Cu" "F.Mask" "F.Paste")
			(net 612 "/FPGA MSS/LPDDR4.DQ14")
			(pinfunction "MSS_DDR_DQ14")
			(pintype "bidirectional")
			(die_length 6.40444)
		)
		(pad "Y9" smd circle
			(at -2 6.799 270)
			(size 0.45 0.45)
			(layers "F.Cu" "F.Mask" "F.Paste")
			(net 613 "/FPGA MSS/LPDDR4.DQ16")
			(pinfunction "MSS_DDR_DQ16")
			(pintype "bidirectional")
			(die_length 6.5997)
		)
		(pad "Y10" smd circle
			(at -1.2 6.799 270)
			(size 0.45 0.45)
			(layers "F.Cu" "F.Mask" "F.Paste")
			(net 614 "/FPGA MSS/LPDDR4.DMI2")
			(pinfunction "MSS_DDR_DM2")
			(pintype "bidirectional")
			(die_length 6.72065)
		)
		(pad "Y11" smd circle
			(at -0.401 6.799 270)
			(size 0.45 0.45)
			(layers "F.Cu" "F.Mask" "F.Paste")
			(net 615 "/FPGA MSS/LPDDR4.DQ22")
			(pinfunction "MSS_DDR_DQ22")
			(pintype "bidirectional")
			(die_length 7.06682)
		)
		(pad "Y12" smd circle
			(at 0.4 6.799 270)
			(size 0.45 0.45)
			(layers "F.Cu" "F.Mask" "F.Paste")
			(net 48 "+1V8")
			(pinfunction "VDDI0")
			(pintype "passive")
		)
		(pad "Y13" smd circle
			(at 1.199 6.799 270)
			(size 0.45 0.45)
			(layers "F.Cu" "F.Mask" "F.Paste")
			(net 467 "unconnected-(U1A-HSIO89NB0-PadY13)")
			(pinfunction "HSIO89NB0")
			(pintype "bidirectional+no_connect")
			(die_length 5.65691)
		)
		(pad "Y14" smd circle
			(at 1.999 6.799 270)
			(size 0.45 0.45)
			(layers "F.Cu" "F.Mask" "F.Paste")
			(net 468 "unconnected-(U1A-HSIO87PB0{slash}DQS{slash}CCC_NW_PLL0_OUT0-PadY14)")
			(pinfunction "HSIO87PB0/DQS/CCC_NW_PLL0_OUT0")
			(pintype "bidirectional+no_connect")
			(die_length 6.51034)
		)
		(pad "Y15" smd circle
			(at 2.799 6.799 270)
			(size 0.45 0.45)
			(layers "F.Cu" "F.Mask" "F.Paste")
			(net 469 "unconnected-(U1A-HSIO85PB0{slash}CCC_NW_PLL0_OUT1-PadY15)")
			(pinfunction "HSIO85PB0/CCC_NW_PLL0_OUT1")
			(pintype "bidirectional+no_connect")
			(die_length 5.39115)
		)
		(pad "Y16" smd circle
			(at 3.6 6.799 270)
			(size 0.45 0.45)
			(layers "F.Cu" "F.Mask" "F.Paste")
			(net 470 "unconnected-(U1A-HSIO82NB0-PadY16)")
			(pinfunction "HSIO82NB0")
			(pintype "bidirectional+no_connect")
			(die_length 6.52137)
		)
		(pad "Y17" smd circle
			(at 4.4 6.799 270)
			(size 0.45 0.45)
			(layers "F.Cu" "F.Mask" "F.Paste")
			(net 417 "GND")
			(pinfunction "VSS")
			(pintype "passive")
		)
		(pad "Y18" smd circle
			(at 5.2 6.799 270)
			(size 0.45 0.45)
			(layers "F.Cu" "F.Mask" "F.Paste")
			(net 471 "unconnected-(U1A-HSIO80NB0-PadY18)")
			(pinfunction "HSIO80NB0")
			(pintype "bidirectional+no_connect")
			(die_length 7.63395)
		)
		(pad "Y19" smd circle
			(at 5.999 6.799 270)
			(size 0.45 0.45)
			(layers "F.Cu" "F.Mask" "F.Paste")
			(net 472 "unconnected-(U1A-HSIO80PB0{slash}CLKIN_N_6-PadY19)")
			(pinfunction "HSIO80PB0/CLKIN_N_6")
			(pintype "bidirectional+no_connect")
			(die_length 7.64669)
		)
		(pad "Y20" smd circle
			(at 6.799 6.799 270)
			(size 0.45 0.45)
			(layers "F.Cu" "F.Mask" "F.Paste")
			(net 340 "/FPGA HSIO/Crosslink_B1.PCLK")
			(pinfunction "HSIO67PB0/CCC_NE_PLL0_OUT1")
			(pintype "bidirectional")
			(die_length 5.4505)
		)
		(pad "Y21" smd circle
			(at 7.599 6.799 270)
			(size 0.45 0.45)
			(layers "F.Cu" "F.Mask" "F.Paste")
			(net 347 "/FPGA HSIO/Crosslink_B2.VSYNC")
			(pinfunction "HSIO67NB0")
			(pintype "bidirectional")
			(die_length 5.38301)
		)
		(pad "Y22" smd circle
			(at 8.4 6.799 270)
			(size 0.45 0.45)
			(layers "F.Cu" "F.Mask" "F.Paste")
			(net 48 "+1V8")
			(pinfunction "VDDI0")
			(pintype "passive")
		)
	)
)
